(kicad_pcb
	(version 20260206)
	(generator "pcbnew")
	(generator_version "10.0")
	(general
		(thickness 1.6)
		(legacy_teardrops no)
	)
	(paper "A4")
	(title_block
		(title "Bryce Canyon_R.DPB_16317-1_OCP.brd")
		(comment 1 "Bryce Canyon / footprints 1810-1816 of 2099")
	)
	(layers
		(0 "F.Cu" signal "TOP")
		(4 "In1.Cu" signal "L2GND")
		(6 "In2.Cu" signal "L3")
		(8 "In3.Cu" signal "L4VCC")
		(10 "In4.Cu" signal "L5VCC")
		(12 "In5.Cu" signal "L6")
		(14 "In6.Cu" signal "L7GND")
		(2 "B.Cu" signal "BOTTOM")
		(9 "F.Adhes" user "F.Adhesive")
		(11 "B.Adhes" user "B.Adhesive")
		(13 "F.Paste" user "Package Geometry/Pastemask Top")
		(15 "B.Paste" user "Package Geometry/Pastemask Bottom")
		(5 "F.SilkS" user "Ref Des/Silkscreen Top")
		(7 "B.SilkS" user "Ref Des/Silkscreen Bottom")
		(1 "F.Mask" user "Board Geometry/Soldermask Top")
		(3 "B.Mask" user "Board Geometry/Soldermask Bottom")
		(17 "Dwgs.User" user "User.Drawings")
		(19 "Cmts.User" user "User.Comments")
		(21 "Eco1.User" user "User.Eco1")
		(23 "Eco2.User" user "User.Eco2")
		(25 "Edge.Cuts" user "Board Geometry/Outline")
		(27 "Margin" user)
		(31 "F.CrtYd" user "Package Geometry/Place Bound Top")
		(29 "B.CrtYd" user "Package Geometry/Place Bound Bottom")
		(35 "F.Fab" user "Ref Des/Assembly Top")
		(33 "B.Fab" user "Ref Des/Assembly Bottom")
	)
	(footprint ""
		(layer "F.Cu")
		(at 458.1652 -25.6794 180)
		(property "Reference" "Q177"
			(at 0 0 180)
			(layer "F.SilkS")
			(hide yes)
			(effects
				(font
					(size 1.27 1.27)
				)
			)
		)
		(property "Value" "AO4406AL-GP"
			(at -3.707384 -1.5367 180)
			(unlocked yes)
			(layer "F.Fab")
			(hide yes)
			(effects
				(font
					(size 1.016 1.016)
					(thickness 0.1524)
				)
			)
		)
		(property "Device Type" "SOIC8H69"
			(at -3.707384 -3.0607 180)
			(unlocked yes)
			(layer "F.Fab")
			(hide yes)
			(effects
				(font
					(size 1.016 1.016)
					(thickness 0.1524)
				)
			)
		)
		(duplicate_pad_numbers_are_jumpers no)
		(fp_line
			(start 2.1336 1.4224)
			(end 2.1336 -1.4224)
			(stroke
				(width 0.1524)
				(type default)
			)
			(layer "F.SilkS")
		)
		(fp_line
			(start 2.1336 -1.4224)
			(end -2.7432 -1.4224)
			(stroke
				(width 0.1524)
				(type default)
			)
			(layer "F.SilkS")
		)
		(fp_line
			(start -2.1844 -0.0508)
			(end -2.7178 0.508)
			(stroke
				(width 0.1524)
				(type default)
			)
			(layer "F.SilkS")
		)
		(fp_line
			(start -2.6289 3.4417)
			(end -2.6289 1.4732)
			(stroke
				(width 0.381)
				(type default)
			)
			(layer "F.SilkS")
		)
		(fp_line
			(start -2.7178 -0.508)
			(end -2.1844 -0.0508)
			(stroke
				(width 0.1524)
				(type default)
			)
			(layer "F.SilkS")
		)
		(fp_line
			(start -2.7432 1.4224)
			(end 2.1336 1.4224)
			(stroke
				(width 0.1524)
				(type default)
			)
			(layer "F.SilkS")
		)
		(fp_line
			(start -2.7432 1.4224)
			(end -2.6416 1.4224)
			(stroke
				(width 0.1524)
				(type default)
			)
			(layer "F.SilkS")
		)
		(fp_line
			(start -2.7432 -1.4224)
			(end -2.7432 1.4224)
			(stroke
				(width 0.1524)
				(type default)
			)
			(layer "F.SilkS")
		)
		(fp_poly
			(pts
				(xy -2.2098 -1.4224) (xy -2.2098 1.4224) (xy 2.2098 1.4224) (xy 2.2098 -1.4224)
			)
			(stroke
				(width 0)
				(type default)
			)
			(fill yes)
			(layer "F.SilkS")
		)
		(fp_rect
			(start -2.450084 2.999994)
			(end 2.450084 -2.999994)
			(stroke
				(width 0)
				(type default)
			)
			(fill no)
			(layer "F.CrtYd")
		)
		(fp_poly
			(pts
				(xy -2.8194 3.6322) (xy -2.8194 -3.6322) (xy 2.8194 -3.6322) (xy 2.8194 1.18364) (xy 2.450084 1.18364)
				(xy 2.450084 -2.999994) (xy -2.450084 -2.999994) (xy -2.450084 2.999994) (xy 2.450084 2.999994)
				(xy 2.450084 1.18618) (xy 2.8194 1.18618) (xy 2.8194 3.6322)
			)
			(stroke
				(width 0)
				(type default)
			)
			(fill no)
			(layer "F.CrtYd")
		)
		(fp_rect
			(start -2.8194 3.6322)
			(end 2.8194 -3.6322)
			(stroke
				(width 0)
				(type default)
			)
			(fill no)
			(layer "F.Fab")
		)
		(pad "1" smd rect
			(at -1.905 2.54 180)
			(size 0.635 1.651)
			(layers "F.Cu" "F.Mask" "F.Paste")
			(net "P5V_HDD34")
		)
		(pad "2" smd rect
			(at -0.635 2.54 180)
			(size 0.635 1.651)
			(layers "F.Cu" "F.Mask" "F.Paste")
			(net "P5V_HDD34")
		)
		(pad "3" smd rect
			(at 0.635 2.54 180)
			(size 0.635 1.651)
			(layers "F.Cu" "F.Mask" "F.Paste")
			(net "P5V_HDD34")
		)
		(pad "4" smd rect
			(at 1.905 2.54 180)
			(size 0.635 1.651)
			(layers "F.Cu" "F.Mask" "F.Paste")
			(net "SW_HDD_P34")
		)
		(pad "5" smd rect
			(at 1.905 -2.54 180)
			(size 0.635 1.651)
			(layers "F.Cu" "F.Mask" "F.Paste")
			(net "P5V_B_4")
		)
		(pad "6" smd rect
			(at 0.635 -2.54 180)
			(size 0.635 1.651)
			(layers "F.Cu" "F.Mask" "F.Paste")
			(net "P5V_B_4")
		)
		(pad "7" smd rect
			(at -0.635 -2.54 180)
			(size 0.635 1.651)
			(layers "F.Cu" "F.Mask" "F.Paste")
			(net "P5V_B_4")
		)
		(pad "8" smd rect
			(at -1.905 -2.54 180)
			(size 0.635 1.651)
			(layers "F.Cu" "F.Mask" "F.Paste")
			(net "P5V_B_4")
		)
	)
	(footprint ""
		(layer "F.Cu")
		(at 333.629 -40.5892 -90)
		(property "Reference" "R761"
			(at 0 0 270)
			(layer "F.SilkS")
			(hide yes)
			(effects
				(font
					(size 1.27 1.27)
				)
			)
		)
		(property "Value" "2R6F-GP"
			(at -0.0508 -4.8514 270)
			(unlocked yes)
			(layer "F.Fab")
			(hide yes)
			(effects
				(font
					(size 1.016 1.016)
					(thickness 0.1524)
				)
			)
		)
		(property "Device Type" "R1206H26"
			(at 0 -6.3754 270)
			(unlocked yes)
			(layer "F.Fab")
			(hide yes)
			(effects
				(font
					(size 1.016 1.016)
					(thickness 0.1524)
				)
			)
		)
		(duplicate_pad_numbers_are_jumpers no)
		(fp_line
			(start -1.016 2.2352)
			(end -1.016 -2.2352)
			(stroke
				(width 0.1524)
				(type default)
			)
			(layer "F.SilkS")
		)
		(fp_line
			(start 1.016 2.2352)
			(end -1.016 2.2352)
			(stroke
				(width 0.1524)
				(type default)
			)
			(layer "F.SilkS")
		)
		(fp_line
			(start -1.016 -2.2352)
			(end 1.016 -2.2352)
			(stroke
				(width 0.1524)
				(type default)
			)
			(layer "F.SilkS")
		)
		(fp_line
			(start 1.016 -2.2352)
			(end 1.016 2.2352)
			(stroke
				(width 0.1524)
				(type default)
			)
			(layer "F.SilkS")
		)
		(fp_rect
			(start -1.0922 2.3114)
			(end 1.0922 -2.3114)
			(stroke
				(width 0)
				(type default)
			)
			(fill no)
			(layer "F.CrtYd")
		)
		(fp_poly
			(pts
				(xy -1.0922 -2.3114) (xy 1.0922 -2.3114) (xy 1.0922 2.3114) (xy -1.0922 2.3114)
			)
			(stroke
				(width 0)
				(type default)
			)
			(fill no)
			(layer "F.Fab")
		)
		(pad "1" smd rect
			(at 0 -1.397 270)
			(size 1.651 1.27)
			(layers "F.Cu" "F.Mask" "F.Paste")
			(net "P12V_HDD30")
		)
		(pad "2" smd rect
			(at 0 1.397 270)
			(size 1.651 1.27)
			(layers "F.Cu" "F.Mask" "F.Paste")
			(net "12V_PRE_30")
		)
	)
	(footprint ""
		(layer "F.Cu")
		(at 77.978 -139.446 -90)
		(property "Reference" "R407"
			(at 0 0 270)
			(layer "F.SilkS")
			(hide yes)
			(effects
				(font
					(size 1.27 1.27)
				)
			)
		)
		(property "Value" "300KR2F-GP"
			(at 0.064008 -3.993896 270)
			(unlocked yes)
			(layer "F.Fab")
			(hide yes)
			(effects
				(font
					(size 1.016 1.016)
					(thickness 0.1524)
				)
			)
		)
		(property "Device Type" "R402H16"
			(at 0.064008 -5.517896 270)
			(unlocked yes)
			(layer "F.Fab")
			(hide yes)
			(effects
				(font
					(size 1.016 1.016)
					(thickness 0.1524)
				)
			)
		)
		(duplicate_pad_numbers_are_jumpers no)
		(fp_line
			(start -0.508 -0.9398)
			(end -0.508 0.9398)
			(stroke
				(width 0.1524)
				(type default)
			)
			(layer "F.SilkS")
		)
		(fp_line
			(start 0.508 -0.9398)
			(end -0.508 -0.9398)
			(stroke
				(width 0.1524)
				(type default)
			)
			(layer "F.SilkS")
		)
		(fp_rect
			(start -0.508 0.9398)
			(end 0.508 -0.9398)
			(stroke
				(width 0)
				(type default)
			)
			(fill no)
			(layer "F.CrtYd")
		)
		(fp_rect
			(start -0.508 0.9398)
			(end 0.508 -0.9398)
			(stroke
				(width 0)
				(type default)
			)
			(fill no)
			(layer "F.Fab")
		)
		(pad "1" smd custom
			(at 0 -0.4445 270)
			(size 0.1397 0.1397)
			(layers "F.Cu" "F.Mask" "F.Paste")
			(net "SW_HDD_N14")
			(options
				(clearance outline)
				(anchor circle)
			)
			(primitives
				(gr_poly
					(pts
						(arc
							(start -0.1778 -0.2794)
							(mid -0.249642 -0.249642)
							(end -0.2794 -0.1778)
						)
						(arc
							(start -0.2794 0.1778)
							(mid -0.249642 0.249642)
							(end -0.1778 0.2794)
						)
						(arc
							(start 0.1778 0.2794)
							(mid 0.249642 0.249642)
							(end 0.2794 0.1778)
						)
						(arc
							(start 0.2794 -0.1778)
							(mid 0.249642 -0.249642)
							(end 0.1778 -0.2794)
						)
					)
					(width 0)
					(fill yes)
				)
			)
		)
		(pad "2" smd custom
			(at 0 0.4445 270)
			(size 0.1397 0.1397)
			(layers "F.Cu" "F.Mask" "F.Paste")
			(net "P12V_B")
			(options
				(clearance outline)
				(anchor circle)
			)
			(primitives
				(gr_poly
					(pts
						(arc
							(start -0.1778 -0.2794)
							(mid -0.249642 -0.249642)
							(end -0.2794 -0.1778)
						)
						(arc
							(start -0.2794 0.1778)
							(mid -0.249642 0.249642)
							(end -0.1778 0.2794)
						)
						(arc
							(start 0.1778 0.2794)
							(mid 0.249642 0.249642)
							(end 0.2794 0.1778)
						)
						(arc
							(start 0.2794 -0.1778)
							(mid 0.249642 -0.249642)
							(end 0.1778 -0.2794)
						)
					)
					(width 0)
					(fill yes)
				)
			)
		)
	)
	(footprint ""
		(layer "F.Cu")
		(at 109.474 -139.446 -90)
		(property "Reference" "R430"
			(at 0 0 270)
			(layer "F.SilkS")
			(hide yes)
			(effects
				(font
					(size 1.27 1.27)
				)
			)
		)
		(property "Value" "300KR2F-GP"
			(at 0.064008 -3.993896 270)
			(unlocked yes)
			(layer "F.Fab")
			(hide yes)
			(effects
				(font
					(size 1.016 1.016)
					(thickness 0.1524)
				)
			)
		)
		(property "Device Type" "R402H16"
			(at 0.064008 -5.517896 270)
			(unlocked yes)
			(layer "F.Fab")
			(hide yes)
			(effects
				(font
					(size 1.016 1.016)
					(thickness 0.1524)
				)
			)
		)
		(duplicate_pad_numbers_are_jumpers no)
		(fp_line
			(start -0.508 -0.9398)
			(end -0.508 0.9398)
			(stroke
				(width 0.1524)
				(type default)
			)
			(layer "F.SilkS")
		)
		(fp_line
			(start 0.508 -0.9398)
			(end -0.508 -0.9398)
			(stroke
				(width 0.1524)
				(type default)
			)
			(layer "F.SilkS")
		)
		(fp_rect
			(start -0.508 0.9398)
			(end 0.508 -0.9398)
			(stroke
				(width 0)
				(type default)
			)
			(fill no)
			(layer "F.CrtYd")
		)
		(fp_rect
			(start -0.508 0.9398)
			(end 0.508 -0.9398)
			(stroke
				(width 0)
				(type default)
			)
			(fill no)
			(layer "F.Fab")
		)
		(pad "1" smd custom
			(at 0 -0.4445 270)
			(size 0.1397 0.1397)
			(layers "F.Cu" "F.Mask" "F.Paste")
			(net "SW_HDD_N15")
			(options
				(clearance outline)
				(anchor circle)
			)
			(primitives
				(gr_poly
					(pts
						(arc
							(start -0.1778 -0.2794)
							(mid -0.249642 -0.249642)
							(end -0.2794 -0.1778)
						)
						(arc
							(start -0.2794 0.1778)
							(mid -0.249642 0.249642)
							(end -0.1778 0.2794)
						)
						(arc
							(start 0.1778 0.2794)
							(mid 0.249642 0.249642)
							(end 0.2794 0.1778)
						)
						(arc
							(start 0.2794 -0.1778)
							(mid 0.249642 -0.249642)
							(end 0.1778 -0.2794)
						)
					)
					(width 0)
					(fill yes)
				)
			)
		)
		(pad "2" smd custom
			(at 0 0.4445 270)
			(size 0.1397 0.1397)
			(layers "F.Cu" "F.Mask" "F.Paste")
			(net "P12V_B")
			(options
				(clearance outline)
				(anchor circle)
			)
			(primitives
				(gr_poly
					(pts
						(arc
							(start -0.1778 -0.2794)
							(mid -0.249642 -0.249642)
							(end -0.2794 -0.1778)
						)
						(arc
							(start -0.2794 0.1778)
							(mid -0.249642 0.249642)
							(end -0.1778 0.2794)
						)
						(arc
							(start 0.1778 0.2794)
							(mid 0.249642 0.249642)
							(end 0.2794 0.1778)
						)
						(arc
							(start 0.2794 -0.1778)
							(mid 0.249642 -0.249642)
							(end 0.1778 -0.2794)
						)
					)
					(width 0)
					(fill yes)
				)
			)
		)
	)
	(footprint ""
		(layer "F.Cu")
		(at 337.312 -133.858 90)
		(property "Reference" "D18"
			(at 0 0 90)
			(layer "F.SilkS")
			(hide yes)
			(effects
				(font
					(size 1.27 1.27)
				)
			)
		)
		(property "Value" "RB551V30-GP"
			(at 0 -6.7818 90)
			(unlocked yes)
			(layer "F.Fab")
			(hide yes)
			(effects
				(font
					(size 1.016 1.016)
					(thickness 0.1524)
				)
			)
		)
		(property "Device Type" "SOD323AKH38"
			(at 0 -8.6868 90)
			(unlocked yes)
			(layer "F.Fab")
			(hide yes)
			(effects
				(font
					(size 1.016 1.016)
					(thickness 0.1524)
				)
			)
		)
		(duplicate_pad_numbers_are_jumpers no)
		(fp_line
			(start 0.889 -1.9304)
			(end 0.889 2.159)
			(stroke
				(width 0.1524)
				(type default)
			)
			(layer "F.SilkS")
		)
		(fp_line
			(start -0.889 -1.9304)
			(end 0.889 -1.9304)
			(stroke
				(width 0.1524)
				(type default)
			)
			(layer "F.SilkS")
		)
		(fp_line
			(start 0.762 2.0574)
			(end -0.762 2.0574)
			(stroke
				(width 0.508)
				(type default)
			)
			(layer "F.SilkS")
		)
		(fp_line
			(start 0.889 2.159)
			(end -0.889 2.159)
			(stroke
				(width 0.1524)
				(type default)
			)
			(layer "F.SilkS")
		)
		(fp_line
			(start -0.889 2.159)
			(end -0.889 -1.9304)
			(stroke
				(width 0.1524)
				(type default)
			)
			(layer "F.SilkS")
		)
		(fp_rect
			(start -1.016 2.3114)
			(end 1.016 -2.0066)
			(stroke
				(width 0)
				(type default)
			)
			(fill no)
			(layer "F.CrtYd")
		)
		(fp_poly
			(pts
				(xy -1.016 -2.0066) (xy 1.016 -2.0066) (xy 1.016 2.3114) (xy -1.016 2.3114)
			)
			(stroke
				(width 0)
				(type default)
			)
			(fill no)
			(layer "F.Fab")
		)
		(pad "A" smd rect
			(at 0 -1.143 90)
			(size 0.5588 1.016)
			(layers "F.Cu" "F.Mask" "F.Paste")
			(net "SW_HDD_R18")
		)
		(pad "K" smd rect
			(at 0 1.143 90)
			(size 0.5588 1.016)
			(layers "F.Cu" "F.Mask" "F.Paste")
			(net "SW_HDD_N18")
		)
	)
	(footprint ""
		(layer "F.Cu")
		(at 319.786 -13.6271 180)
		(property "Reference" "VIA61"
			(at 0 0 180)
			(layer "F.SilkS")
			(hide yes)
			(effects
				(font
					(size 1.27 1.27)
				)
			)
		)
		(property "Value" "100OHM-8L-2D36MM-L18-GP"
			(at 3.8989 0.5715 180)
			(unlocked yes)
			(layer "F.Fab")
			(hide yes)
			(effects
				(font
					(size 1.016 1.016)
					(thickness 0.1524)
				)
			)
		)
		(property "Device Type" "VIA-PCIE-4P-414097"
			(at 3.8989 -0.9525 180)
			(unlocked yes)
			(layer "F.Fab")
			(hide yes)
			(effects
				(font
					(size 1.016 1.016)
					(thickness 0.1524)
				)
			)
		)
		(duplicate_pad_numbers_are_jumpers no)
		(fp_rect
			(start -2.0701 0.4826)
			(end 2.0701 -0.4826)
			(stroke
				(width 0)
				(type default)
			)
			(fill no)
			(layer "F.CrtYd")
		)
		(fp_rect
			(start -2.0701 0.4826)
			(end 2.0701 -0.4826)
			(stroke
				(width 0)
				(type default)
			)
			(fill no)
			(layer "F.Fab")
		)
		(pad "1" thru_hole circle
			(at -1.5875 0 180)
			(size 0.508 0.508)
			(drill 0.254)
			(layers "*.Cu" "*.Mask")
			(remove_unused_layers no)
			(net "GND")
			(clearance 0.2286)
			(thermal_gap 0.2286)
		)
		(pad "2" thru_hole circle
			(at -0.5715 0 180)
			(size 0.508 0.508)
			(drill 0.254)
			(layers "*.Cu" "*.Mask")
			(remove_unused_layers no)
			(net "PHY_SCC_B_TO_DRV_B_30_DP")
			(clearance 0.2286)
			(thermal_gap 0.2286)
		)
		(pad "3" thru_hole circle
			(at 0.5715 0 180)
			(size 0.508 0.508)
			(drill 0.254)
			(layers "*.Cu" "*.Mask")
			(remove_unused_layers no)
			(net "PHY_SCC_B_TO_DRV_B_30_DN")
			(clearance 0.2286)
			(thermal_gap 0.2286)
		)
		(pad "4" thru_hole circle
			(at 1.5875 0 180)
			(size 0.508 0.508)
			(drill 0.254)
			(layers "*.Cu" "*.Mask")
			(remove_unused_layers no)
			(net "GND")
			(clearance 0.2286)
			(thermal_gap 0.2286)
		)
	)
	(footprint ""
		(layer "F.Cu")
		(at 49.911 -131.572)
		(property "Reference" "R386"
			(at 0 0 0)
			(layer "F.SilkS")
			(hide yes)
			(effects
				(font
					(size 1.27 1.27)
				)
			)
		)
		(property "Value" "0R2J-2-GP"
			(at 0.064008 -3.993896 0)
			(unlocked yes)
			(layer "F.Fab")
			(hide yes)
			(effects
				(font
					(size 1.016 1.016)
					(thickness 0.1524)
				)
			)
		)
		(property "Device Type" "R402H16"
			(at 0.064008 -5.517896 0)
			(unlocked yes)
			(layer "F.Fab")
			(hide yes)
			(effects
				(font
					(size 1.016 1.016)
					(thickness 0.1524)
				)
			)
		)
		(duplicate_pad_numbers_are_jumpers no)
		(fp_line
			(start -0.508 -0.9398)
			(end -0.508 0.9398)
			(stroke
				(width 0.1524)
				(type default)
			)
			(layer "F.SilkS")
		)
		(fp_line
			(start 0.508 -0.9398)
			(end -0.508 -0.9398)
			(stroke
				(width 0.1524)
				(type default)
			)
			(layer "F.SilkS")
		)
		(fp_rect
			(start -0.508 0.9398)
			(end 0.508 -0.9398)
			(stroke
				(width 0)
				(type default)
			)
			(fill no)
			(layer "F.CrtYd")
		)
		(fp_rect
			(start -0.508 0.9398)
			(end 0.508 -0.9398)
			(stroke
				(width 0)
				(type default)
			)
			(fill no)
			(layer "F.Fab")
		)
		(pad "1" smd custom
			(at 0 -0.4445)
			(size 0.1397 0.1397)
			(layers "F.Cu" "F.Mask" "F.Paste")
			(net "SW_HDD_G13")
			(options
				(clearance outline)
				(anchor circle)
			)
			(primitives
				(gr_poly
					(pts
						(arc
							(start -0.1778 -0.2794)
							(mid -0.249642 -0.249642)
							(end -0.2794 -0.1778)
						)
						(arc
							(start -0.2794 0.1778)
							(mid -0.249642 0.249642)
							(end -0.1778 0.2794)
						)
						(arc
							(start 0.1778 0.2794)
							(mid 0.249642 0.249642)
							(end 0.2794 0.1778)
						)
						(arc
							(start 0.2794 -0.1778)
							(mid 0.249642 -0.249642)
							(end 0.1778 -0.2794)
						)
					)
					(width 0)
					(fill yes)
				)
			)
		)
		(pad "2" smd custom
			(at 0 0.4445)
			(size 0.1397 0.1397)
			(layers "F.Cu" "F.Mask" "F.Paste")
			(net "SW_HDD_R13")
			(options
				(clearance outline)
				(anchor circle)
			)
			(primitives
				(gr_poly
					(pts
						(arc
							(start -0.1778 -0.2794)
							(mid -0.249642 -0.249642)
							(end -0.2794 -0.1778)
						)
						(arc
							(start -0.2794 0.1778)
							(mid -0.249642 0.249642)
							(end -0.1778 0.2794)
						)
						(arc
							(start 0.1778 0.2794)
							(mid 0.249642 0.249642)
							(end 0.2794 0.1778)
						)
						(arc
							(start 0.2794 -0.1778)
							(mid 0.249642 -0.249642)
							(end 0.1778 -0.2794)
						)
					)
					(width 0)
					(fill yes)
				)
			)
		)
	)
)
